(kicad_pcb
	(version 20260206)
	(generator "pcbnew")
	(generator_version "10.0")
	(general
		(thickness 1.6)
		(legacy_teardrops no)
	)
	(paper "A4")
	(title_block
		(title "01162023_DA0F0TEBIF0_F0T_Expander_BD_F_brd_V02_OCP.brd")
		(comment 1 "Grand Teton / footprints 7751-7759 of 9728")
	)
	(layers
		(0 "F.Cu" signal "TOP")
		(4 "In1.Cu" signal "GND")
		(6 "In2.Cu" signal "VCC")
		(8 "In3.Cu" signal "VCC1")
		(10 "In4.Cu" signal "GND1")
		(12 "In5.Cu" signal "IN1")
		(14 "In6.Cu" signal "GND2")
		(16 "In7.Cu" signal "IN2")
		(18 "In8.Cu" signal "GND3")
		(20 "In9.Cu" signal "IN3")
		(22 "In10.Cu" signal "GND4")
		(24 "In11.Cu" signal "IN4")
		(26 "In12.Cu" signal "GND5")
		(28 "In13.Cu" signal "IN5")
		(30 "In14.Cu" signal "GND6")
		(32 "In15.Cu" signal "IN6")
		(34 "In16.Cu" signal "GND7")
		(2 "B.Cu" signal "BOTTOM")
		(9 "F.Adhes" user "F.Adhesive")
		(11 "B.Adhes" user "B.Adhesive")
		(13 "F.Paste" user "Package Geometry/Pastemask Top")
		(15 "B.Paste" user "Package Geometry/Pastemask Bottom")
		(5 "F.SilkS" user "Ref Des/Silkscreen Top")
		(7 "B.SilkS" user "Ref Des/Silkscreen Bottom")
		(1 "F.Mask" user "Board Geometry/Soldermask Top")
		(3 "B.Mask" user "Board Geometry/Soldermask Bottom")
		(17 "Dwgs.User" user "User.Drawings")
		(19 "Cmts.User" user "User.Comments")
		(21 "Eco1.User" user "User.Eco1")
		(23 "Eco2.User" user "User.Eco2")
		(25 "Edge.Cuts" user "Board Geometry/Outline")
		(27 "Margin" user)
		(31 "F.CrtYd" user "Package Geometry/Place Bound Top")
		(29 "B.CrtYd" user "Package Geometry/Place Bound Bottom")
		(35 "F.Fab" user "Ref Des/Assembly Top")
		(33 "B.Fab" user "Ref Des/Assembly Bottom")
	)
	(footprint ""
		(layer "B.Cu")
		(at 405.393652 -376.492262 90)
		(property "Reference" "R6278"
			(at 0 0 90)
			(layer "B.SilkS")
			(hide yes)
			(effects
				(font
					(size 1.27 1.27)
				)
				(justify mirror)
			)
		)
		(property "Value" ""
			(at 0 0 90)
			(layer "B.Fab")
			(effects
				(font
					(size 1.27 1.27)
				)
				(justify mirror)
			)
		)
		(duplicate_pad_numbers_are_jumpers no)
		(fp_line
			(start 0.7874 -0.4064)
			(end -0.7874 -0.4064)
			(stroke
				(width 0.1524)
				(type default)
			)
			(layer "B.SilkS")
		)
		(fp_line
			(start -0.7874 -0.4064)
			(end -0.7874 0.4064)
			(stroke
				(width 0.1524)
				(type default)
			)
			(layer "B.SilkS")
		)
		(fp_line
			(start 0.7874 0.4064)
			(end 0.7874 -0.4064)
			(stroke
				(width 0.1524)
				(type default)
			)
			(layer "B.SilkS")
		)
		(fp_line
			(start -0.7874 0.4064)
			(end 0.7874 0.4064)
			(stroke
				(width 0.1524)
				(type default)
			)
			(layer "B.SilkS")
		)
		(fp_line
			(start 0.67945 -0.305054)
			(end 0.12065 -0.305054)
			(stroke
				(width 0.1)
				(type default)
			)
			(layer "B.Fab")
		)
		(fp_line
			(start 0.12065 -0.305054)
			(end 0.12065 -0.2794)
			(stroke
				(width 0.1)
				(type default)
			)
			(layer "B.Fab")
		)
		(fp_line
			(start -0.12065 -0.3048)
			(end -0.67945 -0.3048)
			(stroke
				(width 0.1)
				(type default)
			)
			(layer "B.Fab")
		)
		(fp_line
			(start -0.67945 -0.3048)
			(end -0.67945 0.3048)
			(stroke
				(width 0.1)
				(type default)
			)
			(layer "B.Fab")
		)
		(fp_line
			(start 0.12065 -0.2794)
			(end -0.12065 -0.2794)
			(stroke
				(width 0.1)
				(type default)
			)
			(layer "B.Fab")
		)
		(fp_line
			(start -0.12065 -0.2794)
			(end -0.12065 -0.3048)
			(stroke
				(width 0.1)
				(type default)
			)
			(layer "B.Fab")
		)
		(fp_line
			(start 0.12065 0.2794)
			(end 0.12065 0.3048)
			(stroke
				(width 0.1)
				(type default)
			)
			(layer "B.Fab")
		)
		(fp_line
			(start -0.120396 0.2794)
			(end 0.12065 0.2794)
			(stroke
				(width 0.1)
				(type default)
			)
			(layer "B.Fab")
		)
		(fp_line
			(start 0.67945 0.3048)
			(end 0.67945 -0.305054)
			(stroke
				(width 0.1)
				(type default)
			)
			(layer "B.Fab")
		)
		(fp_line
			(start 0.12065 0.3048)
			(end 0.67945 0.3048)
			(stroke
				(width 0.1)
				(type default)
			)
			(layer "B.Fab")
		)
		(fp_line
			(start -0.120396 0.3048)
			(end -0.120396 0.2794)
			(stroke
				(width 0.1)
				(type default)
			)
			(layer "B.Fab")
		)
		(fp_line
			(start -0.67945 0.3048)
			(end -0.120396 0.3048)
			(stroke
				(width 0.1)
				(type default)
			)
			(layer "B.Fab")
		)
		(pad "1" smd circle
			(at 0.40005 0 270)
			(size 0 0)
			(layers "B.Cu" "B.Mask" "B.Paste")
			(net "I3C_MB_BMC_R_SCL")
		)
		(pad "2" smd circle
			(at -0.40005 0 270)
			(size 0 0)
			(layers "B.Cu" "B.Mask" "B.Paste")
			(net "SMB_MB_I3C_ISO_SCL")
		)
	)
	(footprint ""
		(layer "B.Cu")
		(at 117.847364 -282.04033 90)
		(property "Reference" "PR105"
			(at 0 0 90)
			(layer "B.SilkS")
			(hide yes)
			(effects
				(font
					(size 1.27 1.27)
				)
				(justify mirror)
			)
		)
		(property "Value" ""
			(at 0 0 90)
			(layer "B.Fab")
			(effects
				(font
					(size 1.27 1.27)
				)
				(justify mirror)
			)
		)
		(duplicate_pad_numbers_are_jumpers no)
		(fp_line
			(start 0.7874 -0.4064)
			(end -0.7874 -0.4064)
			(stroke
				(width 0.1524)
				(type default)
			)
			(layer "B.SilkS")
		)
		(fp_line
			(start -0.7874 -0.4064)
			(end -0.7874 0.4064)
			(stroke
				(width 0.1524)
				(type default)
			)
			(layer "B.SilkS")
		)
		(fp_line
			(start 0.7874 0.4064)
			(end 0.7874 -0.4064)
			(stroke
				(width 0.1524)
				(type default)
			)
			(layer "B.SilkS")
		)
		(fp_line
			(start -0.7874 0.4064)
			(end 0.7874 0.4064)
			(stroke
				(width 0.1524)
				(type default)
			)
			(layer "B.SilkS")
		)
		(fp_line
			(start 0.67945 -0.305054)
			(end 0.12065 -0.305054)
			(stroke
				(width 0.1)
				(type default)
			)
			(layer "B.Fab")
		)
		(fp_line
			(start 0.12065 -0.305054)
			(end 0.12065 -0.2794)
			(stroke
				(width 0.1)
				(type default)
			)
			(layer "B.Fab")
		)
		(fp_line
			(start -0.12065 -0.3048)
			(end -0.67945 -0.3048)
			(stroke
				(width 0.1)
				(type default)
			)
			(layer "B.Fab")
		)
		(fp_line
			(start -0.67945 -0.3048)
			(end -0.67945 0.3048)
			(stroke
				(width 0.1)
				(type default)
			)
			(layer "B.Fab")
		)
		(fp_line
			(start 0.12065 -0.2794)
			(end -0.12065 -0.2794)
			(stroke
				(width 0.1)
				(type default)
			)
			(layer "B.Fab")
		)
		(fp_line
			(start -0.12065 -0.2794)
			(end -0.12065 -0.3048)
			(stroke
				(width 0.1)
				(type default)
			)
			(layer "B.Fab")
		)
		(fp_line
			(start 0.12065 0.2794)
			(end 0.12065 0.3048)
			(stroke
				(width 0.1)
				(type default)
			)
			(layer "B.Fab")
		)
		(fp_line
			(start -0.120396 0.2794)
			(end 0.12065 0.2794)
			(stroke
				(width 0.1)
				(type default)
			)
			(layer "B.Fab")
		)
		(fp_line
			(start 0.67945 0.3048)
			(end 0.67945 -0.305054)
			(stroke
				(width 0.1)
				(type default)
			)
			(layer "B.Fab")
		)
		(fp_line
			(start 0.12065 0.3048)
			(end 0.67945 0.3048)
			(stroke
				(width 0.1)
				(type default)
			)
			(layer "B.Fab")
		)
		(fp_line
			(start -0.120396 0.3048)
			(end -0.120396 0.2794)
			(stroke
				(width 0.1)
				(type default)
			)
			(layer "B.Fab")
		)
		(fp_line
			(start -0.67945 0.3048)
			(end -0.120396 0.3048)
			(stroke
				(width 0.1)
				(type default)
			)
			(layer "B.Fab")
		)
		(pad "1" smd circle
			(at 0.40005 0 270)
			(size 0 0)
			(layers "B.Cu" "B.Mask" "B.Paste")
			(net "SW_P0V8_PEX0_VOS2")
		)
		(pad "2" smd circle
			(at -0.40005 0 270)
			(size 0 0)
			(layers "B.Cu" "B.Mask" "B.Paste")
			(net "P0V8_PEX0")
		)
	)
	(footprint ""
		(layer "B.Cu")
		(at 53.949854 -290.199826 90)
		(property "Reference" "C1206"
			(at 0 0 90)
			(layer "B.SilkS")
			(hide yes)
			(effects
				(font
					(size 1.27 1.27)
				)
				(justify mirror)
			)
		)
		(property "Value" ""
			(at 0 0 90)
			(layer "B.Fab")
			(effects
				(font
					(size 1.27 1.27)
				)
				(justify mirror)
			)
		)
		(duplicate_pad_numbers_are_jumpers no)
		(fp_line
			(start 0.299974 -0.150114)
			(end -0.299974 -0.150114)
			(stroke
				(width 0.1)
				(type default)
			)
			(layer "B.Fab")
		)
		(fp_line
			(start -0.299974 -0.150114)
			(end -0.299974 0.150114)
			(stroke
				(width 0.1)
				(type default)
			)
			(layer "B.Fab")
		)
		(fp_line
			(start 0.299974 0.150114)
			(end 0.299974 -0.150114)
			(stroke
				(width 0.1)
				(type default)
			)
			(layer "B.Fab")
		)
		(fp_line
			(start -0.299974 0.150114)
			(end 0.299974 0.150114)
			(stroke
				(width 0.1)
				(type default)
			)
			(layer "B.Fab")
		)
		(pad "1" smd rect
			(at 0.2667 0 270)
			(size 0.3048 0.381)
			(layers "B.Cu" "B.Mask" "B.Paste")
			(net "P0V8_SERDES_VDDA_PEX0")
		)
		(pad "2" smd rect
			(at -0.2667 0 270)
			(size 0.3048 0.381)
			(layers "B.Cu" "B.Mask" "B.Paste")
			(net "GND")
		)
	)
	(footprint ""
		(layer "B.Cu")
		(at 348.328488 -304.157634)
		(property "Reference" "PR127"
			(at 0 0 0)
			(layer "B.SilkS")
			(hide yes)
			(effects
				(font
					(size 1.27 1.27)
				)
				(justify mirror)
			)
		)
		(property "Value" ""
			(at 0 0 0)
			(layer "B.Fab")
			(effects
				(font
					(size 1.27 1.27)
				)
				(justify mirror)
			)
		)
		(duplicate_pad_numbers_are_jumpers no)
		(fp_line
			(start -0.7874 -0.4064)
			(end -0.7874 0.4064)
			(stroke
				(width 0.1524)
				(type default)
			)
			(layer "B.SilkS")
		)
		(fp_line
			(start -0.7874 0.4064)
			(end 0.7874 0.4064)
			(stroke
				(width 0.1524)
				(type default)
			)
			(layer "B.SilkS")
		)
		(fp_line
			(start 0.7874 -0.4064)
			(end -0.7874 -0.4064)
			(stroke
				(width 0.1524)
				(type default)
			)
			(layer "B.SilkS")
		)
		(fp_line
			(start 0.7874 0.4064)
			(end 0.7874 -0.4064)
			(stroke
				(width 0.1524)
				(type default)
			)
			(layer "B.SilkS")
		)
		(fp_line
			(start -0.67945 -0.3048)
			(end -0.67945 0.3048)
			(stroke
				(width 0.1)
				(type default)
			)
			(layer "B.Fab")
		)
		(fp_line
			(start -0.67945 0.3048)
			(end -0.120396 0.3048)
			(stroke
				(width 0.1)
				(type default)
			)
			(layer "B.Fab")
		)
		(fp_line
			(start -0.12065 -0.3048)
			(end -0.67945 -0.3048)
			(stroke
				(width 0.1)
				(type default)
			)
			(layer "B.Fab")
		)
		(fp_line
			(start -0.12065 -0.2794)
			(end -0.12065 -0.3048)
			(stroke
				(width 0.1)
				(type default)
			)
			(layer "B.Fab")
		)
		(fp_line
			(start -0.120396 0.2794)
			(end 0.12065 0.2794)
			(stroke
				(width 0.1)
				(type default)
			)
			(layer "B.Fab")
		)
		(fp_line
			(start -0.120396 0.3048)
			(end -0.120396 0.2794)
			(stroke
				(width 0.1)
				(type default)
			)
			(layer "B.Fab")
		)
		(fp_line
			(start 0.12065 -0.305054)
			(end 0.12065 -0.2794)
			(stroke
				(width 0.1)
				(type default)
			)
			(layer "B.Fab")
		)
		(fp_line
			(start 0.12065 -0.2794)
			(end -0.12065 -0.2794)
			(stroke
				(width 0.1)
				(type default)
			)
			(layer "B.Fab")
		)
		(fp_line
			(start 0.12065 0.2794)
			(end 0.12065 0.3048)
			(stroke
				(width 0.1)
				(type default)
			)
			(layer "B.Fab")
		)
		(fp_line
			(start 0.12065 0.3048)
			(end 0.67945 0.3048)
			(stroke
				(width 0.1)
				(type default)
			)
			(layer "B.Fab")
		)
		(fp_line
			(start 0.67945 -0.305054)
			(end 0.12065 -0.305054)
			(stroke
				(width 0.1)
				(type default)
			)
			(layer "B.Fab")
		)
		(fp_line
			(start 0.67945 0.3048)
			(end 0.67945 -0.305054)
			(stroke
				(width 0.1)
				(type default)
			)
			(layer "B.Fab")
		)
		(pad "1" smd circle
			(at 0.40005 0 180)
			(size 0 0)
			(layers "B.Cu" "B.Mask" "B.Paste")
			(net "SH_P0V8_PEX2_RGND2")
		)
		(pad "2" smd circle
			(at -0.40005 0 180)
			(size 0 0)
			(layers "B.Cu" "B.Mask" "B.Paste")
			(net "GND")
		)
	)
	(footprint ""
		(layer "B.Cu")
		(at 295.649904 -292.099746 90)
		(property "Reference" "C1720"
			(at 0 0 90)
			(layer "B.SilkS")
			(hide yes)
			(effects
				(font
					(size 1.27 1.27)
				)
				(justify mirror)
			)
		)
		(property "Value" ""
			(at 0 0 90)
			(layer "B.Fab")
			(effects
				(font
					(size 1.27 1.27)
				)
				(justify mirror)
			)
		)
		(duplicate_pad_numbers_are_jumpers no)
		(fp_line
			(start 0.299974 -0.150114)
			(end -0.299974 -0.150114)
			(stroke
				(width 0.1)
				(type default)
			)
			(layer "B.Fab")
		)
		(fp_line
			(start -0.299974 -0.150114)
			(end -0.299974 0.150114)
			(stroke
				(width 0.1)
				(type default)
			)
			(layer "B.Fab")
		)
		(fp_line
			(start 0.299974 0.150114)
			(end 0.299974 -0.150114)
			(stroke
				(width 0.1)
				(type default)
			)
			(layer "B.Fab")
		)
		(fp_line
			(start -0.299974 0.150114)
			(end 0.299974 0.150114)
			(stroke
				(width 0.1)
				(type default)
			)
			(layer "B.Fab")
		)
		(pad "1" smd rect
			(at 0.2667 0 270)
			(size 0.3048 0.381)
			(layers "B.Cu" "B.Mask" "B.Paste")
			(net "P0V8_SERDES_VDDA_PEX2")
		)
		(pad "2" smd rect
			(at -0.2667 0 270)
			(size 0.3048 0.381)
			(layers "B.Cu" "B.Mask" "B.Paste")
			(net "GND")
		)
	)
	(footprint ""
		(layer "B.Cu")
		(at 63.470282 -296.37482)
		(property "Reference" "C1130"
			(at 0 0 0)
			(layer "B.SilkS")
			(hide yes)
			(effects
				(font
					(size 1.27 1.27)
				)
				(justify mirror)
			)
		)
		(property "Value" ""
			(at 0 0 0)
			(layer "B.Fab")
			(effects
				(font
					(size 1.27 1.27)
				)
				(justify mirror)
			)
		)
		(duplicate_pad_numbers_are_jumpers no)
		(fp_line
			(start -0.299974 -0.150114)
			(end -0.299974 0.150114)
			(stroke
				(width 0.1)
				(type default)
			)
			(layer "B.Fab")
		)
		(fp_line
			(start -0.299974 0.150114)
			(end 0.299974 0.150114)
			(stroke
				(width 0.1)
				(type default)
			)
			(layer "B.Fab")
		)
		(fp_line
			(start 0.299974 -0.150114)
			(end -0.299974 -0.150114)
			(stroke
				(width 0.1)
				(type default)
			)
			(layer "B.Fab")
		)
		(fp_line
			(start 0.299974 0.150114)
			(end 0.299974 -0.150114)
			(stroke
				(width 0.1)
				(type default)
			)
			(layer "B.Fab")
		)
		(pad "1" smd rect
			(at 0.2667 0 180)
			(size 0.3048 0.381)
			(layers "B.Cu" "B.Mask" "B.Paste")
			(net "P0V8_PEX0")
		)
		(pad "2" smd rect
			(at -0.2667 0 180)
			(size 0.3048 0.381)
			(layers "B.Cu" "B.Mask" "B.Paste")
			(net "GND")
		)
	)
	(footprint ""
		(layer "B.Cu")
		(at 104.135174 -390.013444 -90)
		(property "Reference" "C3629"
			(at 0 0 90)
			(layer "B.SilkS")
			(hide yes)
			(effects
				(font
					(size 1.27 1.27)
				)
				(justify mirror)
			)
		)
		(property "Value" ""
			(at 0 0 90)
			(layer "B.Fab")
			(effects
				(font
					(size 1.27 1.27)
				)
				(justify mirror)
			)
		)
		(duplicate_pad_numbers_are_jumpers no)
		(fp_line
			(start -0.7874 0.4064)
			(end 0.7874 0.4064)
			(stroke
				(width 0.1524)
				(type default)
			)
			(layer "B.SilkS")
		)
		(fp_line
			(start 0.7874 0.4064)
			(end 0.7874 -0.4064)
			(stroke
				(width 0.1524)
				(type default)
			)
			(layer "B.SilkS")
		)
		(fp_line
			(start -0.7874 -0.4064)
			(end -0.7874 0.4064)
			(stroke
				(width 0.1524)
				(type default)
			)
			(layer "B.SilkS")
		)
		(fp_line
			(start 0.7874 -0.4064)
			(end -0.7874 -0.4064)
			(stroke
				(width 0.1524)
				(type default)
			)
			(layer "B.SilkS")
		)
		(fp_line
			(start -0.67945 0.3048)
			(end -0.120396 0.3048)
			(stroke
				(width 0.1)
				(type default)
			)
			(layer "B.Fab")
		)
		(fp_line
			(start -0.120396 0.3048)
			(end -0.120396 0.2794)
			(stroke
				(width 0.1)
				(type default)
			)
			(layer "B.Fab")
		)
		(fp_line
			(start 0.12065 0.3048)
			(end 0.67945 0.3048)
			(stroke
				(width 0.1)
				(type default)
			)
			(layer "B.Fab")
		)
		(fp_line
			(start 0.67945 0.3048)
			(end 0.67945 -0.305054)
			(stroke
				(width 0.1)
				(type default)
			)
			(layer "B.Fab")
		)
		(fp_line
			(start -0.120396 0.2794)
			(end 0.12065 0.2794)
			(stroke
				(width 0.1)
				(type default)
			)
			(layer "B.Fab")
		)
		(fp_line
			(start 0.12065 0.2794)
			(end 0.12065 0.3048)
			(stroke
				(width 0.1)
				(type default)
			)
			(layer "B.Fab")
		)
		(fp_line
			(start -0.12065 -0.2794)
			(end -0.12065 -0.3048)
			(stroke
				(width 0.1)
				(type default)
			)
			(layer "B.Fab")
		)
		(fp_line
			(start 0.12065 -0.2794)
			(end -0.12065 -0.2794)
			(stroke
				(width 0.1)
				(type default)
			)
			(layer "B.Fab")
		)
		(fp_line
			(start -0.67945 -0.3048)
			(end -0.67945 0.3048)
			(stroke
				(width 0.1)
				(type default)
			)
			(layer "B.Fab")
		)
		(fp_line
			(start -0.12065 -0.3048)
			(end -0.67945 -0.3048)
			(stroke
				(width 0.1)
				(type default)
			)
			(layer "B.Fab")
		)
		(fp_line
			(start 0.12065 -0.305054)
			(end 0.12065 -0.2794)
			(stroke
				(width 0.1)
				(type default)
			)
			(layer "B.Fab")
		)
		(fp_line
			(start 0.67945 -0.305054)
			(end 0.12065 -0.305054)
			(stroke
				(width 0.1)
				(type default)
			)
			(layer "B.Fab")
		)
		(pad "1" smd circle
			(at 0.40005 0 90)
			(size 0 0)
			(layers "B.Cu" "B.Mask" "B.Paste")
			(net "P3V3_BIC_USB_HUB")
		)
		(pad "2" smd circle
			(at -0.40005 0 90)
			(size 0 0)
			(layers "B.Cu" "B.Mask" "B.Paste")
			(net "GND")
		)
	)
	(footprint ""
		(layer "B.Cu")
		(at 176.224946 -293.99992 -90)
		(property "Reference" "C1406"
			(at 0 0 90)
			(layer "B.SilkS")
			(hide yes)
			(effects
				(font
					(size 1.27 1.27)
				)
				(justify mirror)
			)
		)
		(property "Value" ""
			(at 0 0 90)
			(layer "B.Fab")
			(effects
				(font
					(size 1.27 1.27)
				)
				(justify mirror)
			)
		)
		(duplicate_pad_numbers_are_jumpers no)
		(fp_line
			(start -0.299974 0.150114)
			(end 0.299974 0.150114)
			(stroke
				(width 0.1)
				(type default)
			)
			(layer "B.Fab")
		)
		(fp_line
			(start 0.299974 0.150114)
			(end 0.299974 -0.150114)
			(stroke
				(width 0.1)
				(type default)
			)
			(layer "B.Fab")
		)
		(fp_line
			(start -0.299974 -0.150114)
			(end -0.299974 0.150114)
			(stroke
				(width 0.1)
				(type default)
			)
			(layer "B.Fab")
		)
		(fp_line
			(start 0.299974 -0.150114)
			(end -0.299974 -0.150114)
			(stroke
				(width 0.1)
				(type default)
			)
			(layer "B.Fab")
		)
		(pad "1" smd rect
			(at 0.2667 0 90)
			(size 0.3048 0.381)
			(layers "B.Cu" "B.Mask" "B.Paste")
			(net "P0V8_PEX1")
		)
		(pad "2" smd rect
			(at -0.2667 0 90)
			(size 0.3048 0.381)
			(layers "B.Cu" "B.Mask" "B.Paste")
			(net "GND")
		)
	)
	(footprint ""
		(layer "B.Cu")
		(at 62.974982 -286.399732 90)
		(property "Reference" "C2969"
			(at 0 0 90)
			(layer "B.SilkS")
			(hide yes)
			(effects
				(font
					(size 1.27 1.27)
				)
				(justify mirror)
			)
		)
		(property "Value" ""
			(at 0 0 90)
			(layer "B.Fab")
			(effects
				(font
					(size 1.27 1.27)
				)
				(justify mirror)
			)
		)
		(duplicate_pad_numbers_are_jumpers no)
		(fp_line
			(start 0.299974 -0.150114)
			(end -0.299974 -0.150114)
			(stroke
				(width 0.1)
				(type default)
			)
			(layer "B.Fab")
		)
		(fp_line
			(start -0.299974 -0.150114)
			(end -0.299974 0.150114)
			(stroke
				(width 0.1)
				(type default)
			)
			(layer "B.Fab")
		)
		(fp_line
			(start 0.299974 0.150114)
			(end 0.299974 -0.150114)
			(stroke
				(width 0.1)
				(type default)
			)
			(layer "B.Fab")
		)
		(fp_line
			(start -0.299974 0.150114)
			(end 0.299974 0.150114)
			(stroke
				(width 0.1)
				(type default)
			)
			(layer "B.Fab")
		)
		(pad "1" smd rect
			(at 0.2667 0 270)
			(size 0.3048 0.381)
			(layers "B.Cu" "B.Mask" "B.Paste")
			(net "P1V25_SERDES_VDDPLL_PEX0")
		)
		(pad "2" smd rect
			(at -0.2667 0 270)
			(size 0.3048 0.381)
			(layers "B.Cu" "B.Mask" "B.Paste")
			(net "GND")
		)
	)
)
